(kicad_pcb
	(version 20260206)
	(generator "pcbnew")
	(generator_version "10.0")
	(general
		(thickness 1.6)
		(legacy_teardrops no)
	)
	(paper "A4")
	(title_block
		(title "01162023_DA0F0TEBIF0_F0T_Expander_BD_F_brd_V02_OCP.brd")
		(comment 1 "Grand Teton / footprints 8850-8856 of 9728")
	)
	(layers
		(0 "F.Cu" signal "TOP")
		(4 "In1.Cu" signal "GND")
		(6 "In2.Cu" signal "VCC")
		(8 "In3.Cu" signal "VCC1")
		(10 "In4.Cu" signal "GND1")
		(12 "In5.Cu" signal "IN1")
		(14 "In6.Cu" signal "GND2")
		(16 "In7.Cu" signal "IN2")
		(18 "In8.Cu" signal "GND3")
		(20 "In9.Cu" signal "IN3")
		(22 "In10.Cu" signal "GND4")
		(24 "In11.Cu" signal "IN4")
		(26 "In12.Cu" signal "GND5")
		(28 "In13.Cu" signal "IN5")
		(30 "In14.Cu" signal "GND6")
		(32 "In15.Cu" signal "IN6")
		(34 "In16.Cu" signal "GND7")
		(2 "B.Cu" signal "BOTTOM")
		(9 "F.Adhes" user "F.Adhesive")
		(11 "B.Adhes" user "B.Adhesive")
		(13 "F.Paste" user "Package Geometry/Pastemask Top")
		(15 "B.Paste" user "Package Geometry/Pastemask Bottom")
		(5 "F.SilkS" user "Ref Des/Silkscreen Top")
		(7 "B.SilkS" user "Ref Des/Silkscreen Bottom")
		(1 "F.Mask" user "Board Geometry/Soldermask Top")
		(3 "B.Mask" user "Board Geometry/Soldermask Bottom")
		(17 "Dwgs.User" user "User.Drawings")
		(19 "Cmts.User" user "User.Comments")
		(21 "Eco1.User" user "User.Eco1")
		(23 "Eco2.User" user "User.Eco2")
		(25 "Edge.Cuts" user "Board Geometry/Outline")
		(27 "Margin" user)
		(31 "F.CrtYd" user "Package Geometry/Place Bound Top")
		(29 "B.CrtYd" user "Package Geometry/Place Bound Bottom")
		(35 "F.Fab" user "Ref Des/Assembly Top")
		(33 "B.Fab" user "Ref Des/Assembly Bottom")
	)
	(footprint ""
		(layer "B.Cu")
		(at 302.044354 -229.370636 90)
		(property "Reference" "U309"
			(at -1.453896 2.279904 270)
			(unlocked yes)
			(layer "B.SilkS")
			(effects
				(font
					(size 0.7874 0.5842)
					(thickness 0.1524)
				)
				(justify left mirror)
			)
		)
		(property "Value" ""
			(at 0 0 90)
			(layer "B.Fab")
			(effects
				(font
					(size 1.27 1.27)
				)
				(justify mirror)
			)
		)
		(duplicate_pad_numbers_are_jumpers no)
		(fp_line
			(start 1.0414 -1.575054)
			(end 0.254 -1.575054)
			(stroke
				(width 0.1524)
				(type default)
			)
			(layer "B.SilkS")
		)
		(fp_line
			(start -0.2286 -1.575054)
			(end 0 -1.272032)
			(stroke
				(width 0.1524)
				(type default)
			)
			(layer "B.SilkS")
		)
		(fp_line
			(start -0.254 -1.575054)
			(end -1.0414 -1.575054)
			(stroke
				(width 0.1524)
				(type default)
			)
			(layer "B.SilkS")
		)
		(fp_line
			(start -1.0414 -1.575054)
			(end -1.0414 1.575054)
			(stroke
				(width 0.1524)
				(type default)
			)
			(layer "B.SilkS")
		)
		(fp_line
			(start 0 -1.272032)
			(end 0.254 -1.575054)
			(stroke
				(width 0.1524)
				(type default)
			)
			(layer "B.SilkS")
		)
		(fp_line
			(start 1.0414 1.575054)
			(end 1.0414 -1.575054)
			(stroke
				(width 0.1524)
				(type default)
			)
			(layer "B.SilkS")
		)
		(fp_line
			(start -1.0414 1.575054)
			(end 1.0414 1.575054)
			(stroke
				(width 0.1524)
				(type default)
			)
			(layer "B.SilkS")
		)
		(fp_poly
			(pts
				(xy 2.710688 -1.209294) (xy 3.726688 -1.717294) (xy 3.726688 -0.701294)
			)
			(stroke
				(width 0)
				(type default)
			)
			(fill yes)
			(layer "B.SilkS")
		)
		(fp_line
			(start 1.4478 -1.5748)
			(end -1.4478 -1.5748)
			(stroke
				(width 0.1)
				(type default)
			)
			(layer "B.Fab")
		)
		(fp_line
			(start -1.4478 -1.5748)
			(end -1.4478 -1.2192)
			(stroke
				(width 0.1)
				(type default)
			)
			(layer "B.Fab")
		)
		(fp_line
			(start 2.5654 -1.2192)
			(end 1.4478 -1.2192)
			(stroke
				(width 0.1)
				(type default)
			)
			(layer "B.Fab")
		)
		(fp_line
			(start 1.4478 -1.2192)
			(end 1.4478 -1.5748)
			(stroke
				(width 0.1)
				(type default)
			)
			(layer "B.Fab")
		)
		(fp_line
			(start -1.4478 -1.2192)
			(end -2.5654 -1.2192)
			(stroke
				(width 0.1)
				(type default)
			)
			(layer "B.Fab")
		)
		(fp_line
			(start -2.5654 -1.2192)
			(end -2.5654 1.2192)
			(stroke
				(width 0.1)
				(type default)
			)
			(layer "B.Fab")
		)
		(fp_line
			(start 2.5654 1.2192)
			(end 2.5654 -1.2192)
			(stroke
				(width 0.1)
				(type default)
			)
			(layer "B.Fab")
		)
		(fp_line
			(start 1.4478 1.2192)
			(end 2.5654 1.2192)
			(stroke
				(width 0.1)
				(type default)
			)
			(layer "B.Fab")
		)
		(fp_line
			(start -1.4478 1.2192)
			(end -1.4478 1.5748)
			(stroke
				(width 0.1)
				(type default)
			)
			(layer "B.Fab")
		)
		(fp_line
			(start -2.5654 1.2192)
			(end -1.4478 1.2192)
			(stroke
				(width 0.1)
				(type default)
			)
			(layer "B.Fab")
		)
		(fp_line
			(start 1.4478 1.5748)
			(end 1.4478 1.2192)
			(stroke
				(width 0.1)
				(type default)
			)
			(layer "B.Fab")
		)
		(fp_line
			(start -1.4478 1.5748)
			(end 1.4478 1.5748)
			(stroke
				(width 0.1)
				(type default)
			)
			(layer "B.Fab")
		)
		(fp_poly
			(pts
				(xy 2.710688 -0.975106) (xy 3.726688 -1.483106) (xy 3.726688 -0.467106)
			)
			(stroke
				(width 0)
				(type default)
			)
			(fill yes)
			(layer "B.Fab")
		)
		(pad "1" smd rect
			(at 1.849882 -0.975106)
			(size 0.3556 1.3208)
			(layers "B.Cu" "B.Mask" "B.Paste")
			(net "RST_GPU_PERST_0_R_N")
		)
		(pad "2" smd rect
			(at 1.849882 -0.32512)
			(size 0.3556 1.3208)
			(layers "B.Cu" "B.Mask" "B.Paste")
			(net "RST_GPU_PERST_2_BUF_N")
		)
		(pad "3" smd rect
			(at 1.849882 0.32512)
			(size 0.3556 1.3208)
			(layers "B.Cu" "B.Mask" "B.Paste")
			(net "RST_GPU_PERST_1_R_N")
		)
		(pad "4" smd rect
			(at 1.849882 0.975106)
			(size 0.3556 1.3208)
			(layers "B.Cu" "B.Mask" "B.Paste")
			(net "GND")
		)
		(pad "5" smd rect
			(at -1.849882 0.975106)
			(size 0.3556 1.3208)
			(layers "B.Cu" "B.Mask" "B.Paste")
			(net "RST_GPU_PERST_1_BUF_N")
		)
		(pad "6" smd rect
			(at -1.849882 0.32512)
			(size 0.3556 1.3208)
			(layers "B.Cu" "B.Mask" "B.Paste")
			(net "RST_GPU_PERST_2_R_N")
		)
		(pad "7" smd rect
			(at -1.849882 -0.32512)
			(size 0.3556 1.3208)
			(layers "B.Cu" "B.Mask" "B.Paste")
			(net "RST_GPU_PERST_0_BUF_N")
		)
		(pad "8" smd rect
			(at -1.849882 -0.975106)
			(size 0.3556 1.3208)
			(layers "B.Cu" "B.Mask" "B.Paste")
			(net "P3V3_AUX")
		)
	)
	(footprint ""
		(layer "B.Cu")
		(at 165.655244 -155.0416)
		(property "Reference" "R129"
			(at 0 0 0)
			(layer "B.SilkS")
			(hide yes)
			(effects
				(font
					(size 1.27 1.27)
				)
				(justify mirror)
			)
		)
		(property "Value" ""
			(at 0 0 0)
			(layer "B.Fab")
			(effects
				(font
					(size 1.27 1.27)
				)
				(justify mirror)
			)
		)
		(duplicate_pad_numbers_are_jumpers no)
		(fp_line
			(start -0.7874 -0.4064)
			(end -0.7874 0.4064)
			(stroke
				(width 0.1524)
				(type default)
			)
			(layer "B.SilkS")
		)
		(fp_line
			(start -0.7874 0.4064)
			(end 0.7874 0.4064)
			(stroke
				(width 0.1524)
				(type default)
			)
			(layer "B.SilkS")
		)
		(fp_line
			(start 0.7874 -0.4064)
			(end -0.7874 -0.4064)
			(stroke
				(width 0.1524)
				(type default)
			)
			(layer "B.SilkS")
		)
		(fp_line
			(start 0.7874 0.4064)
			(end 0.7874 -0.4064)
			(stroke
				(width 0.1524)
				(type default)
			)
			(layer "B.SilkS")
		)
		(fp_line
			(start -0.67945 -0.3048)
			(end -0.67945 0.3048)
			(stroke
				(width 0.1)
				(type default)
			)
			(layer "B.Fab")
		)
		(fp_line
			(start -0.67945 0.3048)
			(end -0.120396 0.3048)
			(stroke
				(width 0.1)
				(type default)
			)
			(layer "B.Fab")
		)
		(fp_line
			(start -0.12065 -0.3048)
			(end -0.67945 -0.3048)
			(stroke
				(width 0.1)
				(type default)
			)
			(layer "B.Fab")
		)
		(fp_line
			(start -0.12065 -0.2794)
			(end -0.12065 -0.3048)
			(stroke
				(width 0.1)
				(type default)
			)
			(layer "B.Fab")
		)
		(fp_line
			(start -0.120396 0.2794)
			(end 0.12065 0.2794)
			(stroke
				(width 0.1)
				(type default)
			)
			(layer "B.Fab")
		)
		(fp_line
			(start -0.120396 0.3048)
			(end -0.120396 0.2794)
			(stroke
				(width 0.1)
				(type default)
			)
			(layer "B.Fab")
		)
		(fp_line
			(start 0.12065 -0.305054)
			(end 0.12065 -0.2794)
			(stroke
				(width 0.1)
				(type default)
			)
			(layer "B.Fab")
		)
		(fp_line
			(start 0.12065 -0.2794)
			(end -0.12065 -0.2794)
			(stroke
				(width 0.1)
				(type default)
			)
			(layer "B.Fab")
		)
		(fp_line
			(start 0.12065 0.2794)
			(end 0.12065 0.3048)
			(stroke
				(width 0.1)
				(type default)
			)
			(layer "B.Fab")
		)
		(fp_line
			(start 0.12065 0.3048)
			(end 0.67945 0.3048)
			(stroke
				(width 0.1)
				(type default)
			)
			(layer "B.Fab")
		)
		(fp_line
			(start 0.67945 -0.305054)
			(end 0.12065 -0.305054)
			(stroke
				(width 0.1)
				(type default)
			)
			(layer "B.Fab")
		)
		(fp_line
			(start 0.67945 0.3048)
			(end 0.67945 -0.305054)
			(stroke
				(width 0.1)
				(type default)
			)
			(layer "B.Fab")
		)
		(pad "1" smd circle
			(at 0.40005 0 180)
			(size 0 0)
			(layers "B.Cu" "B.Mask" "B.Paste")
			(net "NIC2_SLOT_ID1")
		)
		(pad "2" smd circle
			(at -0.40005 0 180)
			(size 0 0)
			(layers "B.Cu" "B.Mask" "B.Paste")
			(net "P3V3_NIC2")
		)
	)
	(footprint ""
		(layer "B.Cu")
		(at 351.787968 -284.796738 -90)
		(property "Reference" "PC173"
			(at 0 0 90)
			(layer "B.SilkS")
			(hide yes)
			(effects
				(font
					(size 1.27 1.27)
				)
				(justify mirror)
			)
		)
		(property "Value" ""
			(at 0 0 90)
			(layer "B.Fab")
			(effects
				(font
					(size 1.27 1.27)
				)
				(justify mirror)
			)
		)
		(duplicate_pad_numbers_are_jumpers no)
		(fp_line
			(start -1.524 0.762)
			(end 1.524 0.762)
			(stroke
				(width 0.1524)
				(type default)
			)
			(layer "B.SilkS")
		)
		(fp_line
			(start 1.524 0.762)
			(end 1.524 -0.762)
			(stroke
				(width 0.1524)
				(type default)
			)
			(layer "B.SilkS")
		)
		(fp_line
			(start -1.524 -0.762)
			(end -1.524 0.762)
			(stroke
				(width 0.1524)
				(type default)
			)
			(layer "B.SilkS")
		)
		(fp_line
			(start 1.524 -0.762)
			(end -1.524 -0.762)
			(stroke
				(width 0.1524)
				(type default)
			)
			(layer "B.SilkS")
		)
		(fp_line
			(start -1.1049 0.724916)
			(end -1.1049 -0.724916)
			(stroke
				(width 0.1)
				(type default)
			)
			(layer "B.Fab")
		)
		(fp_line
			(start 1.1049 0.724916)
			(end -1.1049 0.724916)
			(stroke
				(width 0.1)
				(type default)
			)
			(layer "B.Fab")
		)
		(fp_line
			(start -1.1049 -0.724916)
			(end 1.1049 -0.724916)
			(stroke
				(width 0.1)
				(type default)
			)
			(layer "B.Fab")
		)
		(fp_line
			(start 1.1049 -0.724916)
			(end 1.1049 0.724916)
			(stroke
				(width 0.1)
				(type default)
			)
			(layer "B.Fab")
		)
		(pad "1" smd rect
			(at 0.889 0 270)
			(size 1.016 1.27)
			(layers "B.Cu" "B.Mask" "B.Paste")
			(net "SW_P12V_P0V8_PEX3_FLT")
		)
		(pad "2" smd rect
			(at -0.889 0 270)
			(size 1.016 1.27)
			(layers "B.Cu" "B.Mask" "B.Paste")
			(net "GND")
		)
	)
	(footprint ""
		(layer "B.Cu")
		(at 296.599864 -288.299906 90)
		(property "Reference" "C3275"
			(at 0 0 90)
			(layer "B.SilkS")
			(hide yes)
			(effects
				(font
					(size 1.27 1.27)
				)
				(justify mirror)
			)
		)
		(property "Value" ""
			(at 0 0 90)
			(layer "B.Fab")
			(effects
				(font
					(size 1.27 1.27)
				)
				(justify mirror)
			)
		)
		(duplicate_pad_numbers_are_jumpers no)
		(fp_line
			(start 0.299974 -0.150114)
			(end -0.299974 -0.150114)
			(stroke
				(width 0.1)
				(type default)
			)
			(layer "B.Fab")
		)
		(fp_line
			(start -0.299974 -0.150114)
			(end -0.299974 0.150114)
			(stroke
				(width 0.1)
				(type default)
			)
			(layer "B.Fab")
		)
		(fp_line
			(start 0.299974 0.150114)
			(end 0.299974 -0.150114)
			(stroke
				(width 0.1)
				(type default)
			)
			(layer "B.Fab")
		)
		(fp_line
			(start -0.299974 0.150114)
			(end 0.299974 0.150114)
			(stroke
				(width 0.1)
				(type default)
			)
			(layer "B.Fab")
		)
		(pad "1" smd rect
			(at 0.2667 0 270)
			(size 0.3048 0.381)
			(layers "B.Cu" "B.Mask" "B.Paste")
			(net "P1V25_PEX2")
		)
		(pad "2" smd rect
			(at -0.2667 0 270)
			(size 0.3048 0.381)
			(layers "B.Cu" "B.Mask" "B.Paste")
			(net "GND")
		)
	)
	(footprint ""
		(layer "B.Cu")
		(at 409.849828 -301.599854 -90)
		(property "Reference" "C2002"
			(at 0 0 90)
			(layer "B.SilkS")
			(hide yes)
			(effects
				(font
					(size 1.27 1.27)
				)
				(justify mirror)
			)
		)
		(property "Value" ""
			(at 0 0 90)
			(layer "B.Fab")
			(effects
				(font
					(size 1.27 1.27)
				)
				(justify mirror)
			)
		)
		(duplicate_pad_numbers_are_jumpers no)
		(fp_line
			(start -0.299974 0.150114)
			(end 0.299974 0.150114)
			(stroke
				(width 0.1)
				(type default)
			)
			(layer "B.Fab")
		)
		(fp_line
			(start 0.299974 0.150114)
			(end 0.299974 -0.150114)
			(stroke
				(width 0.1)
				(type default)
			)
			(layer "B.Fab")
		)
		(fp_line
			(start -0.299974 -0.150114)
			(end -0.299974 0.150114)
			(stroke
				(width 0.1)
				(type default)
			)
			(layer "B.Fab")
		)
		(fp_line
			(start 0.299974 -0.150114)
			(end -0.299974 -0.150114)
			(stroke
				(width 0.1)
				(type default)
			)
			(layer "B.Fab")
		)
		(pad "1" smd rect
			(at 0.2667 0 90)
			(size 0.3048 0.381)
			(layers "B.Cu" "B.Mask" "B.Paste")
			(net "P0V8_SERDES_VDDA_PEX3")
		)
		(pad "2" smd rect
			(at -0.2667 0 90)
			(size 0.3048 0.381)
			(layers "B.Cu" "B.Mask" "B.Paste")
			(net "GND")
		)
	)
	(footprint ""
		(layer "B.Cu")
		(at 303.559972 -236.736636 90)
		(property "Reference" "R6175"
			(at 0 0 90)
			(layer "B.SilkS")
			(hide yes)
			(effects
				(font
					(size 1.27 1.27)
				)
				(justify mirror)
			)
		)
		(property "Value" ""
			(at 0 0 90)
			(layer "B.Fab")
			(effects
				(font
					(size 1.27 1.27)
				)
				(justify mirror)
			)
		)
		(duplicate_pad_numbers_are_jumpers no)
		(fp_line
			(start 0.7874 -0.4064)
			(end -0.7874 -0.4064)
			(stroke
				(width 0.1524)
				(type default)
			)
			(layer "B.SilkS")
		)
		(fp_line
			(start -0.7874 -0.4064)
			(end -0.7874 0.4064)
			(stroke
				(width 0.1524)
				(type default)
			)
			(layer "B.SilkS")
		)
		(fp_line
			(start 0.7874 0.4064)
			(end 0.7874 -0.4064)
			(stroke
				(width 0.1524)
				(type default)
			)
			(layer "B.SilkS")
		)
		(fp_line
			(start -0.7874 0.4064)
			(end 0.7874 0.4064)
			(stroke
				(width 0.1524)
				(type default)
			)
			(layer "B.SilkS")
		)
		(fp_line
			(start 0.67945 -0.305054)
			(end 0.12065 -0.305054)
			(stroke
				(width 0.1)
				(type default)
			)
			(layer "B.Fab")
		)
		(fp_line
			(start 0.12065 -0.305054)
			(end 0.12065 -0.2794)
			(stroke
				(width 0.1)
				(type default)
			)
			(layer "B.Fab")
		)
		(fp_line
			(start -0.12065 -0.3048)
			(end -0.67945 -0.3048)
			(stroke
				(width 0.1)
				(type default)
			)
			(layer "B.Fab")
		)
		(fp_line
			(start -0.67945 -0.3048)
			(end -0.67945 0.3048)
			(stroke
				(width 0.1)
				(type default)
			)
			(layer "B.Fab")
		)
		(fp_line
			(start 0.12065 -0.2794)
			(end -0.12065 -0.2794)
			(stroke
				(width 0.1)
				(type default)
			)
			(layer "B.Fab")
		)
		(fp_line
			(start -0.12065 -0.2794)
			(end -0.12065 -0.3048)
			(stroke
				(width 0.1)
				(type default)
			)
			(layer "B.Fab")
		)
		(fp_line
			(start 0.12065 0.2794)
			(end 0.12065 0.3048)
			(stroke
				(width 0.1)
				(type default)
			)
			(layer "B.Fab")
		)
		(fp_line
			(start -0.120396 0.2794)
			(end 0.12065 0.2794)
			(stroke
				(width 0.1)
				(type default)
			)
			(layer "B.Fab")
		)
		(fp_line
			(start 0.67945 0.3048)
			(end 0.67945 -0.305054)
			(stroke
				(width 0.1)
				(type default)
			)
			(layer "B.Fab")
		)
		(fp_line
			(start 0.12065 0.3048)
			(end 0.67945 0.3048)
			(stroke
				(width 0.1)
				(type default)
			)
			(layer "B.Fab")
		)
		(fp_line
			(start -0.120396 0.3048)
			(end -0.120396 0.2794)
			(stroke
				(width 0.1)
				(type default)
			)
			(layer "B.Fab")
		)
		(fp_line
			(start -0.67945 0.3048)
			(end -0.120396 0.3048)
			(stroke
				(width 0.1)
				(type default)
			)
			(layer "B.Fab")
		)
		(pad "1" smd circle
			(at 0.40005 0 270)
			(size 0 0)
			(layers "B.Cu" "B.Mask" "B.Paste")
			(net "GND")
		)
		(pad "2" smd circle
			(at -0.40005 0 270)
			(size 0 0)
			(layers "B.Cu" "B.Mask" "B.Paste")
			(net "RST_GPU_PERST_1_N")
		)
	)
	(footprint ""
		(layer "B.Cu")
		(at 110.303564 -349.238062 -90)
		(property "Reference" "C4182"
			(at 0 0 90)
			(layer "B.SilkS")
			(hide yes)
			(effects
				(font
					(size 1.27 1.27)
				)
				(justify mirror)
			)
		)
		(property "Value" ""
			(at 0 0 90)
			(layer "B.Fab")
			(effects
				(font
					(size 1.27 1.27)
				)
				(justify mirror)
			)
		)
		(duplicate_pad_numbers_are_jumpers no)
		(fp_line
			(start -1.524 0.762)
			(end 1.524 0.762)
			(stroke
				(width 0.1524)
				(type default)
			)
			(layer "B.SilkS")
		)
		(fp_line
			(start 1.524 0.762)
			(end 1.524 -0.762)
			(stroke
				(width 0.1524)
				(type default)
			)
			(layer "B.SilkS")
		)
		(fp_line
			(start -1.524 -0.762)
			(end -1.524 0.762)
			(stroke
				(width 0.1524)
				(type default)
			)
			(layer "B.SilkS")
		)
		(fp_line
			(start 1.524 -0.762)
			(end -1.524 -0.762)
			(stroke
				(width 0.1524)
				(type default)
			)
			(layer "B.SilkS")
		)
		(fp_line
			(start -1.1049 0.724916)
			(end -1.1049 -0.724916)
			(stroke
				(width 0.1)
				(type default)
			)
			(layer "B.Fab")
		)
		(fp_line
			(start 1.1049 0.724916)
			(end -1.1049 0.724916)
			(stroke
				(width 0.1)
				(type default)
			)
			(layer "B.Fab")
		)
		(fp_line
			(start -1.1049 -0.724916)
			(end 1.1049 -0.724916)
			(stroke
				(width 0.1)
				(type default)
			)
			(layer "B.Fab")
		)
		(fp_line
			(start 1.1049 -0.724916)
			(end 1.1049 0.724916)
			(stroke
				(width 0.1)
				(type default)
			)
			(layer "B.Fab")
		)
		(pad "1" smd rect
			(at 0.889 0 270)
			(size 1.016 1.27)
			(layers "B.Cu" "B.Mask" "B.Paste")
			(net "P3V3_CLK_BUFFER_9ZXL0451E_S3_VZX3P3A")
		)
		(pad "2" smd rect
			(at -0.889 0 270)
			(size 1.016 1.27)
			(layers "B.Cu" "B.Mask" "B.Paste")
			(net "GND")
		)
	)
)
